# BASEBOARD_FAB2 (Tioga Pass) — schematic netlist excerpt (pin names and nets, part order shuffled) for the footprints in the layout excerpt that follows; sources: Cadence DE-HDL packaged netlist, KiCad conversion of Wiwynn_Tioga_Pass_MB.brd

C3M44  CAP  0.22UF 16V 10% X7R  pkg 0402  page 129 : A = DMI_CPU0_PCH_RX_DN<0> ; B = DMI_CPU0_PCH_RX_C_DN<0>
R4P4  RES  49.9 1% CHIP  pkg 0402  page 21 : A = A_CPU0_UPI2_RBIAS ; B = GND
R6W2  RES  10.0K 1% CHIP  pkg 0402  page 137 : A = PD_UV_HIGH_SET ; B = GND

(kicad_pcb
	(version 20260206)
	(generator "pcbnew")
	(generator_version "10.0")
	(general
		(thickness 1.6)
		(legacy_teardrops no)
	)
	(paper "A4")
	(title_block
		(title "Wiwynn_Tioga_Pass_MB.brd")
		(comment 1 "Tioga Pass / footprints 4267-4269 of 4770")
	)
	(layers
		(0 "F.Cu" signal "TOP")
		(4 "In1.Cu" signal "L2GND")
		(6 "In2.Cu" signal "L3")
		(8 "In3.Cu" signal "L4GND")
		(10 "In4.Cu" signal "L5")
		(12 "In5.Cu" signal "L6GND")
		(14 "In6.Cu" signal "L7VCC")
		(16 "In7.Cu" signal "L8VCC")
		(18 "In8.Cu" signal "L9GND")
		(20 "In9.Cu" signal "L10")
		(22 "In10.Cu" signal "L11GND")
		(24 "In11.Cu" signal "L12")
		(26 "In12.Cu" signal "L13GND")
		(2 "B.Cu" signal "BOTTOM")
		(9 "F.Adhes" user "F.Adhesive")
		(11 "B.Adhes" user "B.Adhesive")
		(13 "F.Paste" user "Package Geometry/Pastemask Top")
		(15 "B.Paste" user "Package Geometry/Pastemask Bottom")
		(5 "F.SilkS" user "Ref Des/Silkscreen Top")
		(7 "B.SilkS" user "Ref Des/Silkscreen Bottom")
		(1 "F.Mask" user "Board Geometry/Soldermask Top")
		(3 "B.Mask" user "Board Geometry/Soldermask Bottom")
		(17 "Dwgs.User" user "User.Drawings")
		(19 "Cmts.User" user "User.Comments")
		(21 "Eco1.User" user "User.Eco1")
		(23 "Eco2.User" user "User.Eco2")
		(25 "Edge.Cuts" user "Board Geometry/Outline")
		(27 "Margin" user)
		(31 "F.CrtYd" user "Package Geometry/Place Bound Top")
		(29 "B.CrtYd" user "Package Geometry/Place Bound Bottom")
		(35 "F.Fab" user "Ref Des/Assembly Top")
		(33 "B.Fab" user "Ref Des/Assembly Bottom")
	)
	(footprint ""
		(layer "B.Cu")
		(at 451.7898 -5.5118 90)
		(property "Reference" "R6W2"
			(at 0.8382 -0.67818 90)
			(unlocked yes)
			(layer "B.SilkS")
			(effects
				(font
					(size 0.4064 0.254)
					(thickness 0.1524)
				)
				(justify left mirror)
			)
		)
		(property "Value" ""
			(at 0 0 90)
			(layer "B.Fab")
			(effects
				(font
					(size 1.27 1.27)
				)
				(justify mirror)
			)
		)
		(duplicate_pad_numbers_are_jumpers no)
		(fp_poly
			(pts
				(xy 0.2794 -0.1016) (xy -0.2794 -0.1016) (xy -0.2794 0.9906) (xy 0.2794 0.9906)
			)
			(stroke
				(width 0)
				(type default)
			)
			(fill no)
			(layer "B.CrtYd")
		)
		(fp_line
			(start 0.2794 -0.1016)
			(end 0.2794 0.9906)
			(stroke
				(width 0.1)
				(type default)
			)
			(layer "B.Fab")
		)
		(fp_line
			(start -0.2794 -0.1016)
			(end 0.2794 -0.1016)
			(stroke
				(width 0.1)
				(type default)
			)
			(layer "B.Fab")
		)
		(fp_line
			(start 0.2794 0.9906)
			(end -0.2794 0.9906)
			(stroke
				(width 0.1)
				(type default)
			)
			(layer "B.Fab")
		)
		(fp_line
			(start -0.2794 0.9906)
			(end -0.2794 -0.1016)
			(stroke
				(width 0.1)
				(type default)
			)
			(layer "B.Fab")
		)
		(pad "1" smd rect
			(at 0 0 270)
			(size 0.508 0.508)
			(layers "B.Cu" "B.Mask" "B.Paste")
			(net "PD_UV_HIGH_SET")
		)
		(pad "2" smd rect
			(at 0 0.889 270)
			(size 0.508 0.508)
			(layers "B.Cu" "B.Mask" "B.Paste")
			(net "GND")
		)
		(zone
			(layer "B.Cu")
			(hatch none 0.5)
			(connect_pads
				(clearance 0)
			)
			(min_thickness 0.25)
			(keepout
				(tracks allowed)
				(vias not_allowed)
				(pads allowed)
				(copperpour not_allowed)
				(footprints allowed)
			)
			(placement
				(enabled no)
				(sheetname "")
			)
			(fill
				(thermal_gap 0.5)
				(thermal_bridge_width 0.5)
				(island_removal_mode 0)
			)
			(polygon
				(pts
					(xy 452.0438 -5.7658) (xy 452.0438 -5.2578) (xy 452.4248 -5.2578) (xy 452.4248 -5.7658)
				)
			)
		)
		(zone
			(layer "B.Cu")
			(hatch none 0.5)
			(connect_pads
				(clearance 0)
			)
			(min_thickness 0.25)
			(keepout
				(tracks not_allowed)
				(vias allowed)
				(pads allowed)
				(copperpour not_allowed)
				(footprints allowed)
			)
			(placement
				(enabled no)
				(sheetname "")
			)
			(fill
				(thermal_gap 0.5)
				(thermal_bridge_width 0.5)
				(island_removal_mode 0)
			)
			(polygon
				(pts
					(xy 452.4248 -5.7658) (xy 452.4248 -5.2578) (xy 452.0438 -5.2578) (xy 452.0438 -5.7658)
				)
			)
		)
	)
	(footprint ""
		(layer "B.Cu")
		(at 282.2448 -77.2414 -90)
		(property "Reference" "R4P4"
			(at 0 0 90)
			(layer "B.SilkS")
			(hide yes)
			(effects
				(font
					(size 1.27 1.27)
				)
				(justify mirror)
			)
		)
		(property "Value" ""
			(at 0 0 90)
			(layer "B.Fab")
			(effects
				(font
					(size 1.27 1.27)
				)
				(justify mirror)
			)
		)
		(duplicate_pad_numbers_are_jumpers no)
		(fp_rect
			(start 0.2794 0.9906)
			(end -0.2794 -0.1016)
			(stroke
				(width 0)
				(type default)
			)
			(fill no)
			(layer "B.CrtYd")
		)
		(fp_line
			(start -0.2794 0.9906)
			(end -0.2794 -0.1016)
			(stroke
				(width 0.1)
				(type default)
			)
			(layer "B.Fab")
		)
		(fp_line
			(start 0.2794 0.9906)
			(end -0.2794 0.9906)
			(stroke
				(width 0.1)
				(type default)
			)
			(layer "B.Fab")
		)
		(fp_line
			(start -0.2794 -0.1016)
			(end 0.2794 -0.1016)
			(stroke
				(width 0.1)
				(type default)
			)
			(layer "B.Fab")
		)
		(fp_line
			(start 0.2794 -0.1016)
			(end 0.2794 0.9906)
			(stroke
				(width 0.1)
				(type default)
			)
			(layer "B.Fab")
		)
		(pad "1" smd rect
			(at 0 0 90)
			(size 0.508 0.508)
			(layers "B.Cu" "B.Mask" "B.Paste")
			(net "A_CPU0_UPI2_RBIAS")
		)
		(pad "2" smd rect
			(at 0 0.889 90)
			(size 0.508 0.508)
			(layers "B.Cu" "B.Mask" "B.Paste")
			(net "GND")
		)
		(zone
			(layer "B.Cu")
			(hatch none 0.5)
			(connect_pads
				(clearance 0)
			)
			(min_thickness 0.25)
			(keepout
				(tracks not_allowed)
				(vias allowed)
				(pads allowed)
				(copperpour not_allowed)
				(footprints allowed)
			)
			(placement
				(enabled no)
				(sheetname "")
			)
			(fill
				(thermal_gap 0.5)
				(thermal_bridge_width 0.5)
				(island_removal_mode 0)
			)
			(polygon
				(pts
					(xy 281.6098 -76.9874) (xy 281.9908 -76.9874) (xy 281.9908 -77.4954) (xy 281.6098 -77.4954)
				)
			)
		)
		(zone
			(layer "B.Cu")
			(hatch none 0.5)
			(connect_pads
				(clearance 0)
			)
			(min_thickness 0.25)
			(keepout
				(tracks allowed)
				(vias not_allowed)
				(pads allowed)
				(copperpour not_allowed)
				(footprints allowed)
			)
			(placement
				(enabled no)
				(sheetname "")
			)
			(fill
				(thermal_gap 0.5)
				(thermal_bridge_width 0.5)
				(island_removal_mode 0)
			)
			(polygon
				(pts
					(xy 281.6098 -76.9874) (xy 281.9908 -76.9874) (xy 281.9908 -77.4954) (xy 281.6098 -77.4954)
				)
			)
		)
	)
	(footprint ""
		(layer "B.Cu")
		(at 369.443 -112.395 -90)
		(property "Reference" "C3M44"
			(at 0 0 90)
			(layer "B.SilkS")
			(hide yes)
			(effects
				(font
					(size 1.27 1.27)
				)
				(justify mirror)
			)
		)
		(property "Value" ""
			(at 0 0 90)
			(layer "B.Fab")
			(effects
				(font
					(size 1.27 1.27)
				)
				(justify mirror)
			)
		)
		(duplicate_pad_numbers_are_jumpers no)
		(fp_poly
			(pts
				(xy -0.3048 -0.1016) (xy -0.3048 0.9906) (xy 0.3048 0.9906) (xy 0.3048 -0.1016)
			)
			(stroke
				(width 0)
				(type default)
			)
			(fill no)
			(layer "B.CrtYd")
		)
		(fp_line
			(start -0.3048 0.9906)
			(end -0.3048 -0.1016)
			(stroke
				(width 0.1)
				(type default)
			)
			(layer "B.Fab")
		)
		(fp_line
			(start 0.3048 0.9906)
			(end -0.3048 0.9906)
			(stroke
				(width 0.1)
				(type default)
			)
			(layer "B.Fab")
		)
		(fp_line
			(start -0.3048 -0.1016)
			(end 0.3048 -0.1016)
			(stroke
				(width 0.1)
				(type default)
			)
			(layer "B.Fab")
		)
		(fp_line
			(start 0.3048 -0.1016)
			(end 0.3048 0.9906)
			(stroke
				(width 0.1)
				(type default)
			)
			(layer "B.Fab")
		)
		(pad "1" smd rect
			(at 0 0 90)
			(size 0.508 0.508)
			(layers "B.Cu" "B.Mask" "B.Paste")
			(net "DMI_CPU0_PCH_RX_DN<0>")
		)
		(pad "2" smd rect
			(at 0 0.889 90)
			(size 0.508 0.508)
			(layers "B.Cu" "B.Mask" "B.Paste")
			(net "DMI_CPU0_PCH_RX_C_DN<0>")
		)
		(zone
			(layer "B.Cu")
			(hatch none 0.5)
			(connect_pads
				(clearance 0)
			)
			(min_thickness 0.25)
			(keepout
				(tracks not_allowed)
				(vias allowed)
				(pads allowed)
				(copperpour not_allowed)
				(footprints allowed)
			)
			(placement
				(enabled no)
				(sheetname "")
			)
			(fill
				(thermal_gap 0.5)
				(thermal_bridge_width 0.5)
				(island_removal_mode 0)
			)
			(polygon
				(pts
					(xy 368.808 -112.141) (xy 368.808 -112.649) (xy 369.189 -112.649) (xy 369.189 -112.141)
				)
			)
		)
		(zone
			(layer "B.Cu")
			(hatch none 0.5)
			(connect_pads
				(clearance 0)
			)
			(min_thickness 0.25)
			(keepout
				(tracks allowed)
				(vias not_allowed)
				(pads allowed)
				(copperpour not_allowed)
				(footprints allowed)
			)
			(placement
				(enabled no)
				(sheetname "")
			)
			(fill
				(thermal_gap 0.5)
				(thermal_bridge_width 0.5)
				(island_removal_mode 0)
			)
			(polygon
				(pts
					(xy 369.189 -112.141) (xy 369.189 -112.649) (xy 368.808 -112.649) (xy 368.808 -112.141)
				)
			)
		)
	)
)
